(kicad_pcb
	(version 20260206)
	(generator "pcbnew")
	(generator_version "10.0")
	(general
		(thickness 1.6)
		(legacy_teardrops no)
	)
	(paper "A4")
	(title_block
		(title "v1-chassis-manager — T6M_CM_d_v01_1031_1645.brd")
		(comment 1 "Open CloudServer (Microsoft) / footprints 1567-1576 of 2512")
	)
	(layers
		(0 "F.Cu" signal "TOP")
		(4 "In1.Cu" signal "GND1")
		(6 "In2.Cu" signal "IN1")
		(8 "In3.Cu" signal "VCC1")
		(10 "In4.Cu" signal "VCC2")
		(12 "In5.Cu" signal "GND2")
		(14 "In6.Cu" signal "IN2")
		(16 "In7.Cu" signal "IN3")
		(18 "In8.Cu" signal "GND3")
		(2 "B.Cu" signal "BOTTOM")
		(9 "F.Adhes" user "F.Adhesive")
		(11 "B.Adhes" user "B.Adhesive")
		(13 "F.Paste" user "Package Geometry/Pastemask Top")
		(15 "B.Paste" user "Package Geometry/Pastemask Bottom")
		(5 "F.SilkS" user "Ref Des/Silkscreen Top")
		(7 "B.SilkS" user "Ref Des/Silkscreen Bottom")
		(1 "F.Mask" user "Board Geometry/Soldermask Top")
		(3 "B.Mask" user "Board Geometry/Soldermask Bottom")
		(17 "Dwgs.User" user "User.Drawings")
		(19 "Cmts.User" user "User.Comments")
		(21 "Eco1.User" user "User.Eco1")
		(23 "Eco2.User" user "User.Eco2")
		(25 "Edge.Cuts" user "Board Geometry/Outline")
		(27 "Margin" user)
		(31 "F.CrtYd" user "Package Geometry/Place Bound Top")
		(29 "B.CrtYd" user "Package Geometry/Place Bound Bottom")
		(35 "F.Fab" user "Ref Des/Assembly Top")
		(33 "B.Fab" user "Ref Des/Assembly Bottom")
	)
	(footprint ""
		(layer "B.Cu")
		(at 75.148948 -21.12264 90)
		(property "Reference" "C154"
			(at -5.832348 -0.078486 270)
			(unlocked yes)
			(layer "B.SilkS")
			(effects
				(font
					(size 0.7874 0.5842)
					(thickness 0.1524)
				)
				(justify left mirror)
			)
		)
		(property "Value" ""
			(at 0 0 90)
			(layer "B.Fab")
			(effects
				(font
					(size 1.27 1.27)
				)
				(justify mirror)
			)
		)
		(duplicate_pad_numbers_are_jumpers no)
		(fp_line
			(start 0.7874 -0.4064)
			(end -0.7874 -0.4064)
			(stroke
				(width 0.1524)
				(type default)
			)
			(layer "B.SilkS")
		)
		(fp_line
			(start -0.7874 -0.4064)
			(end -0.7874 0.4064)
			(stroke
				(width 0.1524)
				(type default)
			)
			(layer "B.SilkS")
		)
		(fp_line
			(start 0 0.381)
			(end 0 -0.381)
			(stroke
				(width 0.1524)
				(type default)
			)
			(layer "B.SilkS")
		)
		(fp_line
			(start 0.7874 0.4064)
			(end 0.7874 -0.4064)
			(stroke
				(width 0.1524)
				(type default)
			)
			(layer "B.SilkS")
		)
		(fp_line
			(start -0.7874 0.4064)
			(end 0.7874 0.4064)
			(stroke
				(width 0.1524)
				(type default)
			)
			(layer "B.SilkS")
		)
		(fp_poly
			(pts
				(xy 0.5334 0.254) (xy 0.635 0.254) (xy 0.635 0.2286) (xy 0.635 -0.254) (xy 0.5334 -0.254) (xy 0.5334 -0.2794)
				(xy -0.5334 -0.2794) (xy -0.5334 -0.254) (xy -0.635 -0.254) (xy -0.635 0.254) (xy -0.5334 0.254)
				(xy -0.5334 0.2794) (xy 0.508 0.2794) (xy 0.5334 0.2794)
			)
			(stroke
				(width 0)
				(type default)
			)
			(fill no)
			(layer "B.CrtYd")
		)
		(pad "1" smd rect
			(at -0.40005 0 270)
			(size 0.4572 0.508)
			(layers "B.Cu" "B.Mask" "B.Paste")
			(net "PV_VDDR_NODE1")
		)
		(pad "2" smd rect
			(at 0.40005 0 270)
			(size 0.4572 0.508)
			(layers "B.Cu" "B.Mask" "B.Paste")
			(net "GND")
		)
	)
	(footprint ""
		(layer "B.Cu")
		(at 50.53076 -188.126624 -90)
		(property "Reference" "R855"
			(at -4.318254 0.671576 270)
			(unlocked yes)
			(layer "B.SilkS")
			(effects
				(font
					(size 0.7874 0.5842)
					(thickness 0.1524)
				)
				(justify left mirror)
			)
		)
		(property "Value" ""
			(at 0 0 90)
			(layer "B.Fab")
			(effects
				(font
					(size 1.27 1.27)
				)
				(justify mirror)
			)
		)
		(duplicate_pad_numbers_are_jumpers no)
		(fp_line
			(start -0.7874 0.4064)
			(end 0.7874 0.4064)
			(stroke
				(width 0.1524)
				(type default)
			)
			(layer "B.SilkS")
		)
		(fp_line
			(start 0.7874 0.4064)
			(end 0.7874 -0.4064)
			(stroke
				(width 0.1524)
				(type default)
			)
			(layer "B.SilkS")
		)
		(fp_line
			(start -0.7874 -0.4064)
			(end -0.7874 0.4064)
			(stroke
				(width 0.1524)
				(type default)
			)
			(layer "B.SilkS")
		)
		(fp_line
			(start 0.7874 -0.4064)
			(end -0.7874 -0.4064)
			(stroke
				(width 0.1524)
				(type default)
			)
			(layer "B.SilkS")
		)
		(fp_poly
			(pts
				(xy 0.508 0.2794) (xy 0.508 0.2286) (xy 0.635 0.2286) (xy 0.635 -0.254) (xy 0.5334 -0.254) (xy 0.5334 -0.2794)
				(xy -0.5334 -0.2794) (xy -0.5334 -0.254) (xy -0.635 -0.254) (xy -0.635 0.254) (xy -0.5334 0.254)
				(xy -0.5334 0.2794)
			)
			(stroke
				(width 0)
				(type default)
			)
			(fill no)
			(layer "B.CrtYd")
		)
		(pad "1" smd rect
			(at -0.40005 0 90)
			(size 0.4572 0.508)
			(layers "B.Cu" "B.Mask" "B.Paste")
			(net "PSU3_DC_OK_R")
		)
		(pad "2" smd rect
			(at 0.40005 0 90)
			(size 0.4572 0.508)
			(layers "B.Cu" "B.Mask" "B.Paste")
			(net "GND")
		)
	)
	(footprint ""
		(layer "B.Cu")
		(at 27.969972 -115.223544)
		(property "Reference" "C97"
			(at -2.203958 -0.129794 0)
			(unlocked yes)
			(layer "B.SilkS")
			(effects
				(font
					(size 0.7874 0.5842)
					(thickness 0.1524)
				)
				(justify left mirror)
			)
		)
		(property "Value" ""
			(at 0 0 0)
			(layer "B.Fab")
			(effects
				(font
					(size 1.27 1.27)
				)
				(justify mirror)
			)
		)
		(duplicate_pad_numbers_are_jumpers no)
		(fp_line
			(start -1.905 -0.8636)
			(end -1.905 0.8636)
			(stroke
				(width 0.1524)
				(type default)
			)
			(layer "B.SilkS")
		)
		(fp_line
			(start -1.905 0.8636)
			(end 1.905 0.8636)
			(stroke
				(width 0.1524)
				(type default)
			)
			(layer "B.SilkS")
		)
		(fp_line
			(start 0 0.8382)
			(end 0 -0.8382)
			(stroke
				(width 0.1524)
				(type default)
			)
			(layer "B.SilkS")
		)
		(fp_line
			(start 1.905 -0.8636)
			(end -1.905 -0.8636)
			(stroke
				(width 0.1524)
				(type default)
			)
			(layer "B.SilkS")
		)
		(fp_line
			(start 1.905 0.8636)
			(end 1.905 -0.8636)
			(stroke
				(width 0.1524)
				(type default)
			)
			(layer "B.SilkS")
		)
		(fp_rect
			(start 1.524 0.7366)
			(end -1.524 -0.7366)
			(stroke
				(width 0)
				(type default)
			)
			(fill no)
			(layer "B.CrtYd")
		)
		(pad "1" smd rect
			(at -0.94996 0 180)
			(size 1.1176 1.3716)
			(layers "B.Cu" "B.Mask" "B.Paste")
			(net "P1V05_NODE1")
		)
		(pad "2" smd rect
			(at 0.94996 0 180)
			(size 1.1176 1.3716)
			(layers "B.Cu" "B.Mask" "B.Paste")
			(net "GND")
		)
	)
	(footprint ""
		(layer "B.Cu")
		(at 125.545596 -32.681164 180)
		(property "Reference" "R628"
			(at -2.291334 1.07188 0)
			(unlocked yes)
			(layer "B.SilkS")
			(effects
				(font
					(size 0.7874 0.5842)
					(thickness 0.1524)
				)
				(justify left mirror)
			)
		)
		(property "Value" ""
			(at 0 0 0)
			(layer "B.Fab")
			(effects
				(font
					(size 1.27 1.27)
				)
				(justify mirror)
			)
		)
		(duplicate_pad_numbers_are_jumpers no)
		(fp_line
			(start 0.7874 0.4064)
			(end 0.7874 -0.4064)
			(stroke
				(width 0.1524)
				(type default)
			)
			(layer "B.SilkS")
		)
		(fp_line
			(start 0.7874 -0.4064)
			(end -0.7874 -0.4064)
			(stroke
				(width 0.1524)
				(type default)
			)
			(layer "B.SilkS")
		)
		(fp_line
			(start -0.7874 0.4064)
			(end 0.7874 0.4064)
			(stroke
				(width 0.1524)
				(type default)
			)
			(layer "B.SilkS")
		)
		(fp_line
			(start -0.7874 -0.4064)
			(end -0.7874 0.4064)
			(stroke
				(width 0.1524)
				(type default)
			)
			(layer "B.SilkS")
		)
		(fp_poly
			(pts
				(xy 0.508 0.2794) (xy 0.508 0.2286) (xy 0.635 0.2286) (xy 0.635 -0.254) (xy 0.5334 -0.254) (xy 0.5334 -0.2794)
				(xy -0.5334 -0.2794) (xy -0.5334 -0.254) (xy -0.635 -0.254) (xy -0.635 0.254) (xy -0.5334 0.254)
				(xy -0.5334 0.2794)
			)
			(stroke
				(width 0)
				(type default)
			)
			(fill no)
			(layer "B.CrtYd")
		)
		(pad "1" smd rect
			(at -0.40005 0)
			(size 0.4572 0.508)
			(layers "B.Cu" "B.Mask" "B.Paste")
			(net "P5V_STB_NODE1")
		)
		(pad "2" smd rect
			(at 0.40005 0)
			(size 0.4572 0.508)
			(layers "B.Cu" "B.Mask" "B.Paste")
			(net "SIO_VCCH")
		)
	)
	(footprint ""
		(layer "B.Cu")
		(at 60.118498 -96.696784 -90)
		(property "Reference" "R62"
			(at -6.3627 5.414264 270)
			(unlocked yes)
			(layer "B.SilkS")
			(effects
				(font
					(size 0.7874 0.5842)
					(thickness 0.1524)
				)
				(justify left mirror)
			)
		)
		(property "Value" ""
			(at 0 0 90)
			(layer "B.Fab")
			(effects
				(font
					(size 1.27 1.27)
				)
				(justify mirror)
			)
		)
		(duplicate_pad_numbers_are_jumpers no)
		(fp_line
			(start -0.7874 0.4064)
			(end 0.7874 0.4064)
			(stroke
				(width 0.1524)
				(type default)
			)
			(layer "B.SilkS")
		)
		(fp_line
			(start 0.7874 0.4064)
			(end 0.7874 -0.4064)
			(stroke
				(width 0.1524)
				(type default)
			)
			(layer "B.SilkS")
		)
		(fp_line
			(start -0.7874 -0.4064)
			(end -0.7874 0.4064)
			(stroke
				(width 0.1524)
				(type default)
			)
			(layer "B.SilkS")
		)
		(fp_line
			(start 0.7874 -0.4064)
			(end -0.7874 -0.4064)
			(stroke
				(width 0.1524)
				(type default)
			)
			(layer "B.SilkS")
		)
		(fp_poly
			(pts
				(xy 0.508 0.2794) (xy 0.508 0.2286) (xy 0.635 0.2286) (xy 0.635 -0.254) (xy 0.5334 -0.254) (xy 0.5334 -0.2794)
				(xy -0.5334 -0.2794) (xy -0.5334 -0.254) (xy -0.635 -0.254) (xy -0.635 0.254) (xy -0.5334 0.254)
				(xy -0.5334 0.2794)
			)
			(stroke
				(width 0)
				(type default)
			)
			(fill no)
			(layer "B.CrtYd")
		)
		(pad "1" smd rect
			(at -0.40005 0 90)
			(size 0.4572 0.508)
			(layers "B.Cu" "B.Mask" "B.Paste")
			(net "LPC_CPU_NODE1_LAD1")
		)
		(pad "2" smd rect
			(at 0.40005 0 90)
			(size 0.4572 0.508)
			(layers "B.Cu" "B.Mask" "B.Paste")
			(net "LPC_CPU_NODE1_LAD1_R")
		)
	)
	(footprint ""
		(layer "B.Cu")
		(at 26.432256 -156.570172)
		(property "Reference" "C512"
			(at -2.96926 -0.13335 0)
			(unlocked yes)
			(layer "B.SilkS")
			(effects
				(font
					(size 0.7874 0.5842)
					(thickness 0.1524)
				)
				(justify left mirror)
			)
		)
		(property "Value" ""
			(at 0 0 0)
			(layer "B.Fab")
			(effects
				(font
					(size 1.27 1.27)
				)
				(justify mirror)
			)
		)
		(duplicate_pad_numbers_are_jumpers no)
		(fp_line
			(start -0.7874 -0.4064)
			(end -0.7874 0.4064)
			(stroke
				(width 0.1524)
				(type default)
			)
			(layer "B.SilkS")
		)
		(fp_line
			(start -0.7874 0.4064)
			(end 0.7874 0.4064)
			(stroke
				(width 0.1524)
				(type default)
			)
			(layer "B.SilkS")
		)
		(fp_line
			(start 0 0.381)
			(end 0 -0.381)
			(stroke
				(width 0.1524)
				(type default)
			)
			(layer "B.SilkS")
		)
		(fp_line
			(start 0.7874 -0.4064)
			(end -0.7874 -0.4064)
			(stroke
				(width 0.1524)
				(type default)
			)
			(layer "B.SilkS")
		)
		(fp_line
			(start 0.7874 0.4064)
			(end 0.7874 -0.4064)
			(stroke
				(width 0.1524)
				(type default)
			)
			(layer "B.SilkS")
		)
		(fp_poly
			(pts
				(xy 0.5334 0.254) (xy 0.635 0.254) (xy 0.635 0.2286) (xy 0.635 -0.254) (xy 0.5334 -0.254) (xy 0.5334 -0.2794)
				(xy -0.5334 -0.2794) (xy -0.5334 -0.254) (xy -0.635 -0.254) (xy -0.635 0.254) (xy -0.5334 0.254)
				(xy -0.5334 0.2794) (xy 0.508 0.2794) (xy 0.5334 0.2794)
			)
			(stroke
				(width 0)
				(type default)
			)
			(fill no)
			(layer "B.CrtYd")
		)
		(pad "1" smd rect
			(at -0.40005 0 180)
			(size 0.4572 0.508)
			(layers "B.Cu" "B.Mask" "B.Paste")
			(net "P1V9_LAN1")
		)
		(pad "2" smd rect
			(at 0.40005 0 180)
			(size 0.4572 0.508)
			(layers "B.Cu" "B.Mask" "B.Paste")
			(net "GND")
		)
	)
	(footprint ""
		(layer "B.Cu")
		(at 189.37732 -15.96898 -90)
		(property "Reference" ""
			(at 0 0 90)
			(layer "B.SilkS")
			(hide yes)
			(effects
				(font
					(size 1.27 1.27)
				)
				(justify mirror)
			)
		)
		(property "Value" ""
			(at 0 0 90)
			(layer "B.Fab")
			(effects
				(font
					(size 1.27 1.27)
				)
				(justify mirror)
			)
		)
		(duplicate_pad_numbers_are_jumpers no)
		(fp_poly
			(pts
				(arc
					(start 0 -1.4986)
					(mid 0 1.4986)
					(end 0 -1.4986)
				)
			)
			(stroke
				(width 0)
				(type default)
			)
			(fill no)
			(layer "B.CrtYd")
		)
		(pad "1" smd circle
			(at 0 0 90)
			(size 0.9906 0.9906)
			(layers "B.Cu" "B.Mask" "B.Paste")
			(net "Net_40")
		)
		(zone
			(layer "B.Cu")
			(hatch none 0.5)
			(connect_pads
				(clearance 0)
			)
			(min_thickness 0.25)
			(keepout
				(tracks not_allowed)
				(vias allowed)
				(pads allowed)
				(copperpour not_allowed)
				(footprints allowed)
			)
			(placement
				(enabled no)
				(sheetname "")
			)
			(fill
				(thermal_gap 0.5)
				(thermal_bridge_width 0.5)
				(island_removal_mode 0)
			)
			(polygon
				(pts
					(arc
						(start 191.00292 -15.96898)
						(mid 187.75172 -15.96898)
						(end 191.00292 -15.96898)
					)
				)
			)
		)
	)
	(footprint ""
		(layer "B.Cu")
		(at 63.812674 -82.151728 -90)
		(property "Reference" "C77"
			(at 32.255206 14.433804 270)
			(unlocked yes)
			(layer "B.SilkS")
			(effects
				(font
					(size 0.7874 0.5842)
					(thickness 0.1524)
				)
				(justify left mirror)
			)
		)
		(property "Value" ""
			(at 0 0 90)
			(layer "B.Fab")
			(effects
				(font
					(size 1.27 1.27)
				)
				(justify mirror)
			)
		)
		(duplicate_pad_numbers_are_jumpers no)
		(fp_line
			(start -0.7874 0.4064)
			(end 0.7874 0.4064)
			(stroke
				(width 0.1524)
				(type default)
			)
			(layer "B.SilkS")
		)
		(fp_line
			(start 0.7874 0.4064)
			(end 0.7874 -0.4064)
			(stroke
				(width 0.1524)
				(type default)
			)
			(layer "B.SilkS")
		)
		(fp_line
			(start 0 0.381)
			(end 0 -0.381)
			(stroke
				(width 0.1524)
				(type default)
			)
			(layer "B.SilkS")
		)
		(fp_line
			(start -0.7874 -0.4064)
			(end -0.7874 0.4064)
			(stroke
				(width 0.1524)
				(type default)
			)
			(layer "B.SilkS")
		)
		(fp_line
			(start 0.7874 -0.4064)
			(end -0.7874 -0.4064)
			(stroke
				(width 0.1524)
				(type default)
			)
			(layer "B.SilkS")
		)
		(fp_poly
			(pts
				(xy 0.5334 0.254) (xy 0.635 0.254) (xy 0.635 0.2286) (xy 0.635 -0.254) (xy 0.5334 -0.254) (xy 0.5334 -0.2794)
				(xy -0.5334 -0.2794) (xy -0.5334 -0.254) (xy -0.635 -0.254) (xy -0.635 0.254) (xy -0.5334 0.254)
				(xy -0.5334 0.2794) (xy 0.508 0.2794) (xy 0.5334 0.2794)
			)
			(stroke
				(width 0)
				(type default)
			)
			(fill no)
			(layer "B.CrtYd")
		)
		(pad "1" smd rect
			(at -0.40005 0 90)
			(size 0.4572 0.508)
			(layers "B.Cu" "B.Mask" "B.Paste")
			(net "P1V8_SUS_NODE1")
		)
		(pad "2" smd rect
			(at 0.40005 0 90)
			(size 0.4572 0.508)
			(layers "B.Cu" "B.Mask" "B.Paste")
			(net "GND")
		)
	)
	(footprint ""
		(layer "B.Cu")
		(at 48.42002 -79.147162)
		(property "Reference" "C56"
			(at -14.7574 31.544006 0)
			(unlocked yes)
			(layer "B.SilkS")
			(effects
				(font
					(size 0.7874 0.5842)
					(thickness 0.1524)
				)
				(justify left mirror)
			)
		)
		(property "Value" ""
			(at 0 0 0)
			(layer "B.Fab")
			(effects
				(font
					(size 1.27 1.27)
				)
				(justify mirror)
			)
		)
		(duplicate_pad_numbers_are_jumpers no)
		(fp_line
			(start -0.7874 -0.4064)
			(end -0.7874 0.4064)
			(stroke
				(width 0.1524)
				(type default)
			)
			(layer "B.SilkS")
		)
		(fp_line
			(start -0.7874 0.4064)
			(end 0.7874 0.4064)
			(stroke
				(width 0.1524)
				(type default)
			)
			(layer "B.SilkS")
		)
		(fp_line
			(start 0 0.381)
			(end 0 -0.381)
			(stroke
				(width 0.1524)
				(type default)
			)
			(layer "B.SilkS")
		)
		(fp_line
			(start 0.7874 -0.4064)
			(end -0.7874 -0.4064)
			(stroke
				(width 0.1524)
				(type default)
			)
			(layer "B.SilkS")
		)
		(fp_line
			(start 0.7874 0.4064)
			(end 0.7874 -0.4064)
			(stroke
				(width 0.1524)
				(type default)
			)
			(layer "B.SilkS")
		)
		(fp_poly
			(pts
				(xy 0.5334 0.254) (xy 0.635 0.254) (xy 0.635 0.2286) (xy 0.635 -0.254) (xy 0.5334 -0.254) (xy 0.5334 -0.2794)
				(xy -0.5334 -0.2794) (xy -0.5334 -0.254) (xy -0.635 -0.254) (xy -0.635 0.254) (xy -0.5334 0.254)
				(xy -0.5334 0.2794) (xy 0.508 0.2794) (xy 0.5334 0.2794)
			)
			(stroke
				(width 0)
				(type default)
			)
			(fill no)
			(layer "B.CrtYd")
		)
		(pad "1" smd rect
			(at -0.40005 0 180)
			(size 0.4572 0.508)
			(layers "B.Cu" "B.Mask" "B.Paste")
			(net "P1V05_NODE1")
		)
		(pad "2" smd rect
			(at 0.40005 0 180)
			(size 0.4572 0.508)
			(layers "B.Cu" "B.Mask" "B.Paste")
			(net "GND")
		)
	)
	(footprint ""
		(layer "B.Cu")
		(at 165.210998 -150.30323 180)
		(property "Reference" "C455"
			(at 1.156462 0.177292 0)
			(unlocked yes)
			(layer "B.SilkS")
			(effects
				(font
					(size 0.7874 0.5842)
					(thickness 0.1524)
				)
				(justify left mirror)
			)
		)
		(property "Value" ""
			(at 0 0 0)
			(layer "B.Fab")
			(effects
				(font
					(size 1.27 1.27)
				)
				(justify mirror)
			)
		)
		(duplicate_pad_numbers_are_jumpers no)
		(fp_line
			(start 0.7874 0.4064)
			(end 0.7874 -0.4064)
			(stroke
				(width 0.1524)
				(type default)
			)
			(layer "B.SilkS")
		)
		(fp_line
			(start 0.7874 -0.4064)
			(end -0.7874 -0.4064)
			(stroke
				(width 0.1524)
				(type default)
			)
			(layer "B.SilkS")
		)
		(fp_line
			(start 0 0.381)
			(end 0 -0.381)
			(stroke
				(width 0.1524)
				(type default)
			)
			(layer "B.SilkS")
		)
		(fp_line
			(start -0.7874 0.4064)
			(end 0.7874 0.4064)
			(stroke
				(width 0.1524)
				(type default)
			)
			(layer "B.SilkS")
		)
		(fp_line
			(start -0.7874 -0.4064)
			(end -0.7874 0.4064)
			(stroke
				(width 0.1524)
				(type default)
			)
			(layer "B.SilkS")
		)
		(fp_poly
			(pts
				(xy 0.5334 0.254) (xy 0.635 0.254) (xy 0.635 0.2286) (xy 0.635 -0.254) (xy 0.5334 -0.254) (xy 0.5334 -0.2794)
				(xy -0.5334 -0.2794) (xy -0.5334 -0.254) (xy -0.635 -0.254) (xy -0.635 0.254) (xy -0.5334 0.254)
				(xy -0.5334 0.2794) (xy 0.508 0.2794) (xy 0.5334 0.2794)
			)
			(stroke
				(width 0)
				(type default)
			)
			(fill no)
			(layer "B.CrtYd")
		)
		(pad "1" smd rect
			(at -0.40005 0)
			(size 0.4572 0.508)
			(layers "B.Cu" "B.Mask" "B.Paste")
			(net "P1V9_LAN2")
		)
		(pad "2" smd rect
			(at 0.40005 0)
			(size 0.4572 0.508)
			(layers "B.Cu" "B.Mask" "B.Paste")
			(net "GND")
		)
	)
)
